# SCM (Grand Teton) — schematic netlist excerpt (pin names and nets, part order shuffled) for the footprints in the layout excerpt that follows; sources: Cadence DE-HDL packaged netlist, KiCad conversion of 12092022_DA0F0TMDCD0_F0T_Management_Board_D_brd_V3_OCP.brd

R584  Q_RES  33.2 1% CHIP  pkg 0402LF  page 12 : A = SMB_BMC_MM10_R_SDA ; B = SMB_BMC_MM10_SDA
R486  Q_RES  33.2 1% CHIP  pkg 0402LF  page 45 : A = SPI_PCH_MUXED_IO3 ; B = SPI_PCH_IO3_FLASH_R1

(kicad_pcb
	(version 20260206)
	(generator "pcbnew")
	(generator_version "10.0")
	(general
		(thickness 1.6)
		(legacy_teardrops no)
	)
	(paper "A4")
	(title_block
		(title "12092022_DA0F0TMDCD0_F0T_Management_Board_D_brd_V3_OCP.brd")
		(comment 1 "Grand Teton / footprints 338-339 of 1440")
	)
	(layers
		(0 "F.Cu" signal "TOP")
		(4 "In1.Cu" signal "GND")
		(6 "In2.Cu" signal "IN1")
		(8 "In3.Cu" signal "GND1")
		(10 "In4.Cu" signal "IN2")
		(12 "In5.Cu" signal "VCC")
		(14 "In6.Cu" signal "VCC1")
		(16 "In7.Cu" signal "IN3")
		(18 "In8.Cu" signal "GND2")
		(20 "In9.Cu" signal "IN4")
		(22 "In10.Cu" signal "GND3")
		(2 "B.Cu" signal "BOTTOM")
		(9 "F.Adhes" user "F.Adhesive")
		(11 "B.Adhes" user "B.Adhesive")
		(13 "F.Paste" user "Package Geometry/Pastemask Top")
		(15 "B.Paste" user "Package Geometry/Pastemask Bottom")
		(5 "F.SilkS" user "Ref Des/Silkscreen Top")
		(7 "B.SilkS" user "Ref Des/Silkscreen Bottom")
		(1 "F.Mask" user "Board Geometry/Soldermask Top")
		(3 "B.Mask" user "Board Geometry/Soldermask Bottom")
		(17 "Dwgs.User" user "User.Drawings")
		(19 "Cmts.User" user "User.Comments")
		(21 "Eco1.User" user "User.Eco1")
		(23 "Eco2.User" user "User.Eco2")
		(25 "Edge.Cuts" user "Board Geometry/Outline")
		(27 "Margin" user)
		(31 "F.CrtYd" user "Package Geometry/Place Bound Top")
		(29 "B.CrtYd" user "Package Geometry/Place Bound Bottom")
		(35 "F.Fab" user "Ref Des/Assembly Top")
		(33 "B.Fab" user "Ref Des/Assembly Bottom")
	)
	(footprint ""
		(layer "F.Cu")
		(at 57.222136 -34.637726 -90)
		(property "Reference" "R584"
			(at 0 0 270)
			(layer "F.SilkS")
			(hide yes)
			(effects
				(font
					(size 1.27 1.27)
				)
			)
		)
		(property "Value" ""
			(at 0 0 270)
			(layer "F.Fab")
			(effects
				(font
					(size 1.27 1.27)
				)
			)
		)
		(duplicate_pad_numbers_are_jumpers no)
		(fp_line
			(start -0.7874 0.4064)
			(end -0.7874 -0.4064)
			(stroke
				(width 0.1524)
				(type default)
			)
			(layer "F.SilkS")
		)
		(fp_line
			(start 0.7874 0.4064)
			(end -0.7874 0.4064)
			(stroke
				(width 0.1524)
				(type default)
			)
			(layer "F.SilkS")
		)
		(fp_line
			(start -0.7874 -0.4064)
			(end 0.7874 -0.4064)
			(stroke
				(width 0.1524)
				(type default)
			)
			(layer "F.SilkS")
		)
		(fp_line
			(start 0.7874 -0.4064)
			(end 0.7874 0.4064)
			(stroke
				(width 0.1524)
				(type default)
			)
			(layer "F.SilkS")
		)
		(fp_line
			(start -0.67945 0.3048)
			(end -0.67945 -0.305054)
			(stroke
				(width 0.1)
				(type default)
			)
			(layer "F.Fab")
		)
		(fp_line
			(start -0.12065 0.3048)
			(end -0.67945 0.3048)
			(stroke
				(width 0.1)
				(type default)
			)
			(layer "F.Fab")
		)
		(fp_line
			(start 0.120396 0.3048)
			(end 0.120396 0.2794)
			(stroke
				(width 0.1)
				(type default)
			)
			(layer "F.Fab")
		)
		(fp_line
			(start 0.67945 0.3048)
			(end 0.120396 0.3048)
			(stroke
				(width 0.1)
				(type default)
			)
			(layer "F.Fab")
		)
		(fp_line
			(start -0.12065 0.2794)
			(end -0.12065 0.3048)
			(stroke
				(width 0.1)
				(type default)
			)
			(layer "F.Fab")
		)
		(fp_line
			(start 0.120396 0.2794)
			(end -0.12065 0.2794)
			(stroke
				(width 0.1)
				(type default)
			)
			(layer "F.Fab")
		)
		(fp_line
			(start -0.12065 -0.2794)
			(end 0.12065 -0.2794)
			(stroke
				(width 0.1)
				(type default)
			)
			(layer "F.Fab")
		)
		(fp_line
			(start 0.12065 -0.2794)
			(end 0.12065 -0.3048)
			(stroke
				(width 0.1)
				(type default)
			)
			(layer "F.Fab")
		)
		(fp_line
			(start 0.12065 -0.3048)
			(end 0.67945 -0.3048)
			(stroke
				(width 0.1)
				(type default)
			)
			(layer "F.Fab")
		)
		(fp_line
			(start 0.67945 -0.3048)
			(end 0.67945 0.3048)
			(stroke
				(width 0.1)
				(type default)
			)
			(layer "F.Fab")
		)
		(fp_line
			(start -0.67945 -0.305054)
			(end -0.12065 -0.305054)
			(stroke
				(width 0.1)
				(type default)
			)
			(layer "F.Fab")
		)
		(fp_line
			(start -0.12065 -0.305054)
			(end -0.12065 -0.2794)
			(stroke
				(width 0.1)
				(type default)
			)
			(layer "F.Fab")
		)
		(pad "1" smd circle
			(at -0.40005 0 270)
			(size 0 0)
			(layers "F.Cu" "F.Mask" "F.Paste")
			(net "SMB_BMC_MM10_R_SDA")
		)
		(pad "2" smd circle
			(at 0.40005 0 270)
			(size 0 0)
			(layers "F.Cu" "F.Mask" "F.Paste")
			(net "SMB_BMC_MM10_SDA")
		)
	)
	(footprint ""
		(layer "F.Cu")
		(at 35.1536 -89.3826 180)
		(property "Reference" "R486"
			(at 0 0 180)
			(layer "F.SilkS")
			(hide yes)
			(effects
				(font
					(size 1.27 1.27)
				)
			)
		)
		(property "Value" ""
			(at 0 0 180)
			(layer "F.Fab")
			(effects
				(font
					(size 1.27 1.27)
				)
			)
		)
		(duplicate_pad_numbers_are_jumpers no)
		(fp_line
			(start 0.7874 0.4064)
			(end -0.7874 0.4064)
			(stroke
				(width 0.1524)
				(type default)
			)
			(layer "F.SilkS")
		)
		(fp_line
			(start 0.7874 -0.4064)
			(end 0.7874 0.4064)
			(stroke
				(width 0.1524)
				(type default)
			)
			(layer "F.SilkS")
		)
		(fp_line
			(start -0.7874 0.4064)
			(end -0.7874 -0.4064)
			(stroke
				(width 0.1524)
				(type default)
			)
			(layer "F.SilkS")
		)
		(fp_line
			(start -0.7874 -0.4064)
			(end 0.7874 -0.4064)
			(stroke
				(width 0.1524)
				(type default)
			)
			(layer "F.SilkS")
		)
		(fp_line
			(start 0.67945 0.3048)
			(end 0.120396 0.3048)
			(stroke
				(width 0.1)
				(type default)
			)
			(layer "F.Fab")
		)
		(fp_line
			(start 0.67945 -0.3048)
			(end 0.67945 0.3048)
			(stroke
				(width 0.1)
				(type default)
			)
			(layer "F.Fab")
		)
		(fp_line
			(start 0.12065 -0.2794)
			(end 0.12065 -0.3048)
			(stroke
				(width 0.1)
				(type default)
			)
			(layer "F.Fab")
		)
		(fp_line
			(start 0.12065 -0.3048)
			(end 0.67945 -0.3048)
			(stroke
				(width 0.1)
				(type default)
			)
			(layer "F.Fab")
		)
		(fp_line
			(start 0.120396 0.3048)
			(end 0.120396 0.2794)
			(stroke
				(width 0.1)
				(type default)
			)
			(layer "F.Fab")
		)
		(fp_line
			(start 0.120396 0.2794)
			(end -0.12065 0.2794)
			(stroke
				(width 0.1)
				(type default)
			)
			(layer "F.Fab")
		)
		(fp_line
			(start -0.12065 0.3048)
			(end -0.67945 0.3048)
			(stroke
				(width 0.1)
				(type default)
			)
			(layer "F.Fab")
		)
		(fp_line
			(start -0.12065 0.2794)
			(end -0.12065 0.3048)
			(stroke
				(width 0.1)
				(type default)
			)
			(layer "F.Fab")
		)
		(fp_line
			(start -0.12065 -0.2794)
			(end 0.12065 -0.2794)
			(stroke
				(width 0.1)
				(type default)
			)
			(layer "F.Fab")
		)
		(fp_line
			(start -0.12065 -0.305054)
			(end -0.12065 -0.2794)
			(stroke
				(width 0.1)
				(type default)
			)
			(layer "F.Fab")
		)
		(fp_line
			(start -0.67945 0.3048)
			(end -0.67945 -0.305054)
			(stroke
				(width 0.1)
				(type default)
			)
			(layer "F.Fab")
		)
		(fp_line
			(start -0.67945 -0.305054)
			(end -0.12065 -0.305054)
			(stroke
				(width 0.1)
				(type default)
			)
			(layer "F.Fab")
		)
		(pad "1" smd circle
			(at -0.40005 0 180)
			(size 0 0)
			(layers "F.Cu" "F.Mask" "F.Paste")
			(net "SPI_PCH_MUXED_IO3")
		)
		(pad "2" smd circle
			(at 0.40005 0 180)
			(size 0 0)
			(layers "F.Cu" "F.Mask" "F.Paste")
			(net "SPI_PCH_IO3_FLASH_R1")
		)
	)
)
